(kicad_pcb
	(version 20260206)
	(generator "pcbnew")
	(generator_version "10.0")
	(general
		(thickness 1.6)
		(legacy_teardrops no)
	)
	(paper "A4")
	(title_block
		(title "panther-plus-userver — 13130-1b_20150205.brd")
		(comment 1 "Honey Badger (Wiwynn) / footprints 790-798 of 1509")
	)
	(layers
		(0 "F.Cu" signal "TOP")
		(4 "In1.Cu" signal "L2")
		(6 "In2.Cu" signal "L3")
		(8 "In3.Cu" signal "L4")
		(10 "In4.Cu" signal "L5")
		(12 "In5.Cu" signal "L6")
		(14 "In6.Cu" signal "L7")
		(16 "In7.Cu" signal "L8")
		(18 "In8.Cu" signal "L9")
		(20 "In9.Cu" signal "L10")
		(22 "In10.Cu" signal "L11")
		(2 "B.Cu" signal "BOTTOM")
		(9 "F.Adhes" user "F.Adhesive")
		(11 "B.Adhes" user "B.Adhesive")
		(13 "F.Paste" user "Package Geometry/Pastemask Top")
		(15 "B.Paste" user "Package Geometry/Pastemask Bottom")
		(5 "F.SilkS" user "Ref Des/Silkscreen Top")
		(7 "B.SilkS" user "Ref Des/Silkscreen Bottom")
		(1 "F.Mask" user "Board Geometry/Soldermask Top")
		(3 "B.Mask" user "Board Geometry/Soldermask Bottom")
		(17 "Dwgs.User" user "User.Drawings")
		(19 "Cmts.User" user "User.Comments")
		(21 "Eco1.User" user "User.Eco1")
		(23 "Eco2.User" user "User.Eco2")
		(25 "Edge.Cuts" user "Board Geometry/Outline")
		(27 "Margin" user)
		(31 "F.CrtYd" user "Package Geometry/Place Bound Top")
		(29 "B.CrtYd" user "Package Geometry/Place Bound Bottom")
		(35 "F.Fab" user "Ref Des/Assembly Top")
		(33 "B.Fab" user "Ref Des/Assembly Bottom")
	)
	(footprint ""
		(layer "F.Cu")
		(at 49.022 -44.958 -90)
		(property "Reference" "C20"
			(at 0 0 270)
			(layer "F.SilkS")
			(hide yes)
			(effects
				(font
					(size 1.27 1.27)
				)
			)
		)
		(property "Value" "SC1U25V3KX-GP"
			(at -0.0254 -2.0193 270)
			(unlocked yes)
			(layer "F.Fab")
			(hide yes)
			(effects
				(font
					(size 1.016 1.016)
					(thickness 0.1524)
				)
			)
		)
		(property "Device Type" "C603H36"
			(at -0.0254 -3.5433 270)
			(unlocked yes)
			(layer "F.Fab")
			(hide yes)
			(effects
				(font
					(size 1.016 1.016)
					(thickness 0.1524)
				)
			)
		)
		(duplicate_pad_numbers_are_jumpers no)
		(fp_line
			(start -0.4064 0)
			(end 0.4064 0)
			(stroke
				(width 0.2286)
				(type default)
			)
			(layer "F.SilkS")
		)
		(fp_rect
			(start -0.635 1.1811)
			(end 0.635 -1.1811)
			(stroke
				(width 0)
				(type default)
			)
			(fill no)
			(layer "F.CrtYd")
		)
		(fp_rect
			(start -0.635 1.1811)
			(end 0.635 -1.1811)
			(stroke
				(width 0)
				(type default)
			)
			(fill no)
			(layer "F.Fab")
		)
		(pad "1" smd custom
			(at 0 -0.6604 270)
			(size 0.19685 0.19685)
			(layers "F.Cu" "F.Mask" "F.Paste")
			(net "SW_P3V3_EN_LV_D")
			(options
				(clearance outline)
				(anchor circle)
			)
			(primitives
				(gr_poly
					(pts
						(arc
							(start 0.508 -0.2921)
							(mid 0.478242 -0.363942)
							(end 0.4064 -0.3937)
						)
						(arc
							(start -0.4064 -0.3937)
							(mid -0.478242 -0.363942)
							(end -0.508 -0.2921)
						)
						(arc
							(start -0.508 0.2921)
							(mid -0.478242 0.363942)
							(end -0.4064 0.3937)
						)
						(arc
							(start 0.4064 0.3937)
							(mid 0.478242 0.363942)
							(end 0.508 0.2921)
						)
					)
					(width 0)
					(fill yes)
				)
			)
		)
		(pad "2" smd custom
			(at 0 0.6604 270)
			(size 0.19685 0.19685)
			(layers "F.Cu" "F.Mask" "F.Paste")
			(net "GND")
			(options
				(clearance outline)
				(anchor circle)
			)
			(primitives
				(gr_poly
					(pts
						(arc
							(start 0.508 -0.2921)
							(mid 0.478242 -0.363942)
							(end 0.4064 -0.3937)
						)
						(arc
							(start -0.4064 -0.3937)
							(mid -0.478242 -0.363942)
							(end -0.508 -0.2921)
						)
						(arc
							(start -0.508 0.2921)
							(mid -0.478242 0.363942)
							(end -0.4064 0.3937)
						)
						(arc
							(start 0.4064 0.3937)
							(mid 0.478242 0.363942)
							(end 0.508 0.2921)
						)
					)
					(width 0)
					(fill yes)
				)
			)
		)
	)
	(footprint ""
		(layer "F.Cu")
		(at 23.0632 -52.6034 90)
		(property "Reference" "PC61"
			(at 0 0 90)
			(layer "F.SilkS")
			(hide yes)
			(effects
				(font
					(size 1.27 1.27)
				)
			)
		)
		(property "Value" "SCD068U16V2KX-GP"
			(at 1.8923 -1.2065 90)
			(unlocked yes)
			(layer "F.Fab")
			(hide yes)
			(effects
				(font
					(size 1.016 1.016)
					(thickness 0.1524)
				)
			)
		)
		(property "Device Type" "C402H22"
			(at 1.8923 -2.7305 90)
			(unlocked yes)
			(layer "F.Fab")
			(hide yes)
			(effects
				(font
					(size 1.016 1.016)
					(thickness 0.1524)
				)
			)
		)
		(duplicate_pad_numbers_are_jumpers no)
		(fp_rect
			(start -0.381 0.7366)
			(end 0.381 -0.7366)
			(stroke
				(width 0)
				(type default)
			)
			(fill no)
			(layer "F.CrtYd")
		)
		(fp_rect
			(start -0.381 0.7366)
			(end 0.381 -0.7366)
			(stroke
				(width 0)
				(type default)
			)
			(fill no)
			(layer "F.Fab")
		)
		(pad "1" smd custom
			(at 0 -0.4572 90)
			(size 0.1143 0.1143)
			(layers "F.Cu" "F.Mask" "F.Paste")
			(net "VR_PVCCP_VSEN")
			(options
				(clearance outline)
				(anchor circle)
			)
			(primitives
				(gr_poly
					(pts
						(arc
							(start -0.254 -0.1778)
							(mid -0.239121 -0.213721)
							(end -0.2032 -0.2286)
						)
						(arc
							(start 0.2032 -0.2286)
							(mid 0.239121 -0.213721)
							(end 0.254 -0.1778)
						)
						(arc
							(start 0.254 0.1778)
							(mid 0.239121 0.213721)
							(end 0.2032 0.2286)
						)
						(arc
							(start -0.2032 0.2286)
							(mid -0.239121 0.213721)
							(end -0.254 0.1778)
						)
					)
					(width 0)
					(fill yes)
				)
			)
		)
		(pad "2" smd custom
			(at 0 0.4572 90)
			(size 0.1143 0.1143)
			(layers "F.Cu" "F.Mask" "F.Paste")
			(net "VR_PVCCP_RTN")
			(options
				(clearance outline)
				(anchor circle)
			)
			(primitives
				(gr_poly
					(pts
						(arc
							(start -0.254 -0.1778)
							(mid -0.239121 -0.213721)
							(end -0.2032 -0.2286)
						)
						(arc
							(start 0.2032 -0.2286)
							(mid 0.239121 -0.213721)
							(end 0.254 -0.1778)
						)
						(arc
							(start 0.254 0.1778)
							(mid 0.239121 0.213721)
							(end 0.2032 0.2286)
						)
						(arc
							(start -0.2032 0.2286)
							(mid -0.239121 0.213721)
							(end -0.254 0.1778)
						)
					)
					(width 0)
					(fill yes)
				)
			)
		)
	)
	(footprint ""
		(layer "F.Cu")
		(at 19.9644 -52.6288 -90)
		(property "Reference" "PR93"
			(at 0 0 270)
			(layer "F.SilkS")
			(hide yes)
			(effects
				(font
					(size 1.27 1.27)
				)
			)
		)
		(property "Value" "1KR2F-3-GP"
			(at 1.7907 -1.1176 270)
			(unlocked yes)
			(layer "F.Fab")
			(hide yes)
			(effects
				(font
					(size 1.016 1.016)
					(thickness 0.1524)
				)
			)
		)
		(property "Device Type" "R402H16"
			(at 1.7907 -2.6416 270)
			(unlocked yes)
			(layer "F.Fab")
			(hide yes)
			(effects
				(font
					(size 1.016 1.016)
					(thickness 0.1524)
				)
			)
		)
		(duplicate_pad_numbers_are_jumpers no)
		(fp_rect
			(start -0.381 0.8382)
			(end 0.381 -0.8382)
			(stroke
				(width 0)
				(type default)
			)
			(fill no)
			(layer "F.CrtYd")
		)
		(fp_rect
			(start -0.381 0.8382)
			(end 0.381 -0.8382)
			(stroke
				(width 0)
				(type default)
			)
			(fill no)
			(layer "F.Fab")
		)
		(pad "1" smd custom
			(at 0 -0.4318 270)
			(size 0.127 0.127)
			(layers "F.Cu" "F.Mask" "F.Paste")
			(net "VR_PVCCP_FB")
			(options
				(clearance outline)
				(anchor circle)
			)
			(primitives
				(gr_poly
					(pts
						(arc
							(start -0.2032 -0.2794)
							(mid -0.239121 -0.264521)
							(end -0.254 -0.2286)
						)
						(arc
							(start -0.254 0.2286)
							(mid -0.239121 0.264521)
							(end -0.2032 0.2794)
						)
						(arc
							(start 0.2032 0.2794)
							(mid 0.239121 0.264521)
							(end 0.254 0.2286)
						)
						(arc
							(start 0.254 -0.2286)
							(mid 0.239121 -0.264521)
							(end 0.2032 -0.2794)
						)
					)
					(width 0)
					(fill yes)
				)
			)
		)
		(pad "2" smd custom
			(at 0 0.4318 270)
			(size 0.127 0.127)
			(layers "F.Cu" "F.Mask" "F.Paste")
			(net "VR_PVCCP_FB_RC2")
			(options
				(clearance outline)
				(anchor circle)
			)
			(primitives
				(gr_poly
					(pts
						(arc
							(start -0.2032 -0.2794)
							(mid -0.239121 -0.264521)
							(end -0.254 -0.2286)
						)
						(arc
							(start -0.254 0.2286)
							(mid -0.239121 0.264521)
							(end -0.2032 0.2794)
						)
						(arc
							(start 0.2032 0.2794)
							(mid 0.239121 0.264521)
							(end 0.254 0.2286)
						)
						(arc
							(start 0.254 -0.2286)
							(mid 0.239121 -0.264521)
							(end 0.2032 -0.2794)
						)
					)
					(width 0)
					(fill yes)
				)
			)
		)
	)
	(footprint ""
		(layer "F.Cu")
		(at 71.882 -57.15 90)
		(property "Reference" "R301"
			(at 0 0 90)
			(layer "F.SilkS")
			(hide yes)
			(effects
				(font
					(size 1.27 1.27)
				)
			)
		)
		(property "Value" "4K7R2F-GP"
			(at 0.064008 -3.993896 90)
			(unlocked yes)
			(layer "F.Fab")
			(hide yes)
			(effects
				(font
					(size 1.016 1.016)
					(thickness 0.1524)
				)
			)
		)
		(property "Device Type" "R402H16"
			(at 0.064008 -5.517896 90)
			(unlocked yes)
			(layer "F.Fab")
			(hide yes)
			(effects
				(font
					(size 1.016 1.016)
					(thickness 0.1524)
				)
			)
		)
		(duplicate_pad_numbers_are_jumpers no)
		(fp_rect
			(start -0.381 0.8382)
			(end 0.381 -0.8382)
			(stroke
				(width 0)
				(type default)
			)
			(fill no)
			(layer "F.CrtYd")
		)
		(fp_rect
			(start -0.381 0.8382)
			(end 0.381 -0.8382)
			(stroke
				(width 0)
				(type default)
			)
			(fill no)
			(layer "F.Fab")
		)
		(pad "1" smd custom
			(at 0 -0.4318 90)
			(size 0.127 0.127)
			(layers "F.Cu" "F.Mask" "F.Paste")
			(net "P3V3_STBY")
			(options
				(clearance outline)
				(anchor circle)
			)
			(primitives
				(gr_poly
					(pts
						(arc
							(start -0.2032 -0.2794)
							(mid -0.239121 -0.264521)
							(end -0.254 -0.2286)
						)
						(arc
							(start -0.254 0.2286)
							(mid -0.239121 0.264521)
							(end -0.2032 0.2794)
						)
						(arc
							(start 0.2032 0.2794)
							(mid 0.239121 0.264521)
							(end 0.254 0.2286)
						)
						(arc
							(start 0.254 -0.2286)
							(mid 0.239121 -0.264521)
							(end 0.2032 -0.2794)
						)
					)
					(width 0)
					(fill yes)
				)
			)
		)
		(pad "2" smd custom
			(at 0 0.4318 90)
			(size 0.127 0.127)
			(layers "F.Cu" "F.Mask" "F.Paste")
			(net "BMC_I2C_CLK")
			(options
				(clearance outline)
				(anchor circle)
			)
			(primitives
				(gr_poly
					(pts
						(arc
							(start -0.2032 -0.2794)
							(mid -0.239121 -0.264521)
							(end -0.254 -0.2286)
						)
						(arc
							(start -0.254 0.2286)
							(mid -0.239121 0.264521)
							(end -0.2032 0.2794)
						)
						(arc
							(start 0.2032 0.2794)
							(mid 0.239121 0.264521)
							(end 0.254 0.2286)
						)
						(arc
							(start 0.254 -0.2286)
							(mid 0.239121 -0.264521)
							(end 0.2032 -0.2794)
						)
					)
					(width 0)
					(fill yes)
				)
			)
		)
	)
	(footprint ""
		(layer "F.Cu")
		(at 12.954 -58.293 -90)
		(property "Reference" "TP6"
			(at 0 0 270)
			(layer "F.SilkS")
			(hide yes)
			(effects
				(font
					(size 1.27 1.27)
				)
			)
		)
		(property "Value" "TPAD28-1-GP-U"
			(at 0.0508 -1.9304 270)
			(unlocked yes)
			(layer "F.Fab")
			(hide yes)
			(effects
				(font
					(size 1.016 1.016)
					(thickness 0.1524)
				)
			)
		)
		(property "Device Type" "TPAD28-1-U"
			(at 0.0508 -3.4544 270)
			(unlocked yes)
			(layer "F.Fab")
			(hide yes)
			(effects
				(font
					(size 1.016 1.016)
					(thickness 0.1524)
				)
			)
		)
		(duplicate_pad_numbers_are_jumpers no)
		(fp_poly
			(pts
				(arc
					(start 0 -0.3556)
					(mid 0 0.3556)
					(end 0 -0.3556)
				)
			)
			(stroke
				(width 0)
				(type default)
			)
			(fill no)
			(layer "F.CrtYd")
		)
		(fp_poly
			(pts
				(arc
					(start 0 -0.9525)
					(mid 0 0.9525)
					(end 0 -0.9525)
				)
			)
			(stroke
				(width 0)
				(type default)
			)
			(fill no)
			(layer "F.Fab")
		)
		(pad "1" smd circle
			(at 0 0 270)
			(size 0.7112 0.7112)
			(layers "F.Cu" "F.Mask" "F.Paste")
			(net "TP_PVCCP_CLK")
		)
	)
	(footprint ""
		(layer "F.Cu")
		(at 160.909 -12.828778 180)
		(property "Reference" "C344"
			(at 0 0 180)
			(layer "F.SilkS")
			(hide yes)
			(effects
				(font
					(size 1.27 1.27)
				)
			)
		)
		(property "Value" "SCD1U16V2KX-3GP"
			(at 1.8923 -1.2065 180)
			(unlocked yes)
			(layer "F.Fab")
			(hide yes)
			(effects
				(font
					(size 1.016 1.016)
					(thickness 0.1524)
				)
			)
		)
		(property "Device Type" "C402H22"
			(at 1.8923 -2.7305 180)
			(unlocked yes)
			(layer "F.Fab")
			(hide yes)
			(effects
				(font
					(size 1.016 1.016)
					(thickness 0.1524)
				)
			)
		)
		(duplicate_pad_numbers_are_jumpers no)
		(fp_rect
			(start -0.381 0.7366)
			(end 0.381 -0.7366)
			(stroke
				(width 0)
				(type default)
			)
			(fill no)
			(layer "F.CrtYd")
		)
		(fp_rect
			(start -0.381 0.7366)
			(end 0.381 -0.7366)
			(stroke
				(width 0)
				(type default)
			)
			(fill no)
			(layer "F.Fab")
		)
		(pad "1" smd custom
			(at 0 -0.4572 180)
			(size 0.1143 0.1143)
			(layers "F.Cu" "F.Mask" "F.Paste")
			(net "PV_VDDR")
			(options
				(clearance outline)
				(anchor circle)
			)
			(primitives
				(gr_poly
					(pts
						(arc
							(start -0.254 -0.1778)
							(mid -0.239121 -0.213721)
							(end -0.2032 -0.2286)
						)
						(arc
							(start 0.2032 -0.2286)
							(mid 0.239121 -0.213721)
							(end 0.254 -0.1778)
						)
						(arc
							(start 0.254 0.1778)
							(mid 0.239121 0.213721)
							(end 0.2032 0.2286)
						)
						(arc
							(start -0.2032 0.2286)
							(mid -0.239121 0.213721)
							(end -0.254 0.1778)
						)
					)
					(width 0)
					(fill yes)
				)
			)
		)
		(pad "2" smd custom
			(at 0 0.4572 180)
			(size 0.1143 0.1143)
			(layers "F.Cu" "F.Mask" "F.Paste")
			(net "GND")
			(options
				(clearance outline)
				(anchor circle)
			)
			(primitives
				(gr_poly
					(pts
						(arc
							(start -0.254 -0.1778)
							(mid -0.239121 -0.213721)
							(end -0.2032 -0.2286)
						)
						(arc
							(start 0.2032 -0.2286)
							(mid 0.239121 -0.213721)
							(end 0.254 -0.1778)
						)
						(arc
							(start 0.254 0.1778)
							(mid 0.239121 0.213721)
							(end 0.2032 0.2286)
						)
						(arc
							(start -0.2032 0.2286)
							(mid -0.239121 0.213721)
							(end -0.254 0.1778)
						)
					)
					(width 0)
					(fill yes)
				)
			)
		)
	)
	(footprint ""
		(layer "F.Cu")
		(at 185.039 -43.688 -90)
		(property "Reference" "R222"
			(at 0 0 270)
			(layer "F.SilkS")
			(hide yes)
			(effects
				(font
					(size 1.27 1.27)
				)
			)
		)
		(property "Value" "0R2J-2-GP"
			(at 0.064008 -3.993896 270)
			(unlocked yes)
			(layer "F.Fab")
			(hide yes)
			(effects
				(font
					(size 1.016 1.016)
					(thickness 0.1524)
				)
			)
		)
		(property "Device Type" "R402H16"
			(at 0.064008 -5.517896 270)
			(unlocked yes)
			(layer "F.Fab")
			(hide yes)
			(effects
				(font
					(size 1.016 1.016)
					(thickness 0.1524)
				)
			)
		)
		(duplicate_pad_numbers_are_jumpers no)
		(fp_rect
			(start -0.381 0.8382)
			(end 0.381 -0.8382)
			(stroke
				(width 0)
				(type default)
			)
			(fill no)
			(layer "F.CrtYd")
		)
		(fp_rect
			(start -0.381 0.8382)
			(end 0.381 -0.8382)
			(stroke
				(width 0)
				(type default)
			)
			(fill no)
			(layer "F.Fab")
		)
		(pad "1" smd custom
			(at 0 -0.4318 270)
			(size 0.127 0.127)
			(layers "F.Cu" "F.Mask" "F.Paste")
			(net "PV_VDDR_VREF_B")
			(options
				(clearance outline)
				(anchor circle)
			)
			(primitives
				(gr_poly
					(pts
						(arc
							(start -0.2032 -0.2794)
							(mid -0.239121 -0.264521)
							(end -0.254 -0.2286)
						)
						(arc
							(start -0.254 0.2286)
							(mid -0.239121 0.264521)
							(end -0.2032 0.2794)
						)
						(arc
							(start 0.2032 0.2794)
							(mid 0.239121 0.264521)
							(end 0.254 0.2286)
						)
						(arc
							(start 0.254 -0.2286)
							(mid 0.239121 -0.264521)
							(end 0.2032 -0.2794)
						)
					)
					(width 0)
					(fill yes)
				)
			)
		)
		(pad "2" smd custom
			(at 0 0.4318 270)
			(size 0.127 0.127)
			(layers "F.Cu" "F.Mask" "F.Paste")
			(net "DDR3_M_B_VREF_DQ0")
			(options
				(clearance outline)
				(anchor circle)
			)
			(primitives
				(gr_poly
					(pts
						(arc
							(start -0.2032 -0.2794)
							(mid -0.239121 -0.264521)
							(end -0.254 -0.2286)
						)
						(arc
							(start -0.254 0.2286)
							(mid -0.239121 0.264521)
							(end -0.2032 0.2794)
						)
						(arc
							(start 0.2032 0.2794)
							(mid 0.239121 0.264521)
							(end 0.254 0.2286)
						)
						(arc
							(start 0.254 -0.2286)
							(mid 0.239121 -0.264521)
							(end 0.2032 -0.2794)
						)
					)
					(width 0)
					(fill yes)
				)
			)
		)
	)
	(footprint ""
		(layer "F.Cu")
		(at 15.494 -30.099 -90)
		(property "Reference" "PR100"
			(at 0 0 270)
			(layer "F.SilkS")
			(hide yes)
			(effects
				(font
					(size 1.27 1.27)
				)
			)
		)
		(property "Value" "3D01R5F-GP"
			(at 0 -4.9022 270)
			(unlocked yes)
			(layer "F.Fab")
			(hide yes)
			(effects
				(font
					(size 1.016 1.016)
					(thickness 0.1524)
				)
			)
		)
		(property "Device Type" "R805H24"
			(at 0 -6.8072 270)
			(unlocked yes)
			(layer "F.Fab")
			(hide yes)
			(effects
				(font
					(size 1.016 1.016)
					(thickness 0.1524)
				)
			)
		)
		(duplicate_pad_numbers_are_jumpers no)
		(fp_line
			(start -0.2794 0)
			(end -0.6096 0)
			(stroke
				(width 0.3048)
				(type default)
			)
			(layer "F.SilkS")
		)
		(fp_line
			(start 0.6096 0)
			(end 0.2794 0)
			(stroke
				(width 0.3048)
				(type default)
			)
			(layer "F.SilkS")
		)
		(fp_poly
			(pts
				(xy -0.9017 1.4351) (xy 0.9017 1.4351) (xy 0.9017 -1.4351) (xy -0.9017 -1.4351)
			)
			(stroke
				(width 0)
				(type default)
			)
			(fill no)
			(layer "F.CrtYd")
		)
		(fp_poly
			(pts
				(xy 0.9017 1.4351) (xy 0.9017 -1.4351) (xy -0.9017 -1.4351) (xy -0.9017 1.4351)
			)
			(stroke
				(width 0)
				(type default)
			)
			(fill no)
			(layer "F.Fab")
		)
		(pad "1" smd rect
			(at 0 -0.8382 270)
			(size 1.5494 0.9398)
			(layers "F.Cu" "F.Mask" "F.Paste")
			(net "P1V0_LX")
		)
		(pad "2" smd rect
			(at 0 0.8382 270)
			(size 1.5494 0.9398)
			(layers "F.Cu" "F.Mask" "F.Paste")
			(net "P1V0_SNB")
		)
	)
	(footprint ""
		(layer "F.Cu")
		(at 58.801 -41.783 -90)
		(property "Reference" "R64"
			(at 0 0 270)
			(layer "F.SilkS")
			(hide yes)
			(effects
				(font
					(size 1.27 1.27)
				)
			)
		)
		(property "Value" "4K7R2F-GP"
			(at 1.7907 -1.1176 270)
			(unlocked yes)
			(layer "F.Fab")
			(hide yes)
			(effects
				(font
					(size 1.016 1.016)
					(thickness 0.1524)
				)
			)
		)
		(property "Device Type" "R402H16"
			(at 1.7907 -2.6416 270)
			(unlocked yes)
			(layer "F.Fab")
			(hide yes)
			(effects
				(font
					(size 1.016 1.016)
					(thickness 0.1524)
				)
			)
		)
		(duplicate_pad_numbers_are_jumpers no)
		(fp_rect
			(start -0.381 0.8382)
			(end 0.381 -0.8382)
			(stroke
				(width 0)
				(type default)
			)
			(fill no)
			(layer "F.CrtYd")
		)
		(fp_rect
			(start -0.381 0.8382)
			(end 0.381 -0.8382)
			(stroke
				(width 0)
				(type default)
			)
			(fill no)
			(layer "F.Fab")
		)
		(pad "1" smd custom
			(at 0 -0.4318 270)
			(size 0.127 0.127)
			(layers "F.Cu" "F.Mask" "F.Paste")
			(net "P12V")
			(options
				(clearance outline)
				(anchor circle)
			)
			(primitives
				(gr_poly
					(pts
						(arc
							(start -0.2032 -0.2794)
							(mid -0.239121 -0.264521)
							(end -0.254 -0.2286)
						)
						(arc
							(start -0.254 0.2286)
							(mid -0.239121 0.264521)
							(end -0.2032 0.2794)
						)
						(arc
							(start 0.2032 0.2794)
							(mid 0.239121 0.264521)
							(end 0.254 0.2286)
						)
						(arc
							(start 0.254 -0.2286)
							(mid 0.239121 -0.264521)
							(end 0.2032 -0.2794)
						)
					)
					(width 0)
					(fill yes)
				)
			)
		)
		(pad "2" smd custom
			(at 0 0.4318 270)
			(size 0.127 0.127)
			(layers "F.Cu" "F.Mask" "F.Paste")
			(net "SW_P3V3_LV_G5")
			(options
				(clearance outline)
				(anchor circle)
			)
			(primitives
				(gr_poly
					(pts
						(arc
							(start -0.2032 -0.2794)
							(mid -0.239121 -0.264521)
							(end -0.254 -0.2286)
						)
						(arc
							(start -0.254 0.2286)
							(mid -0.239121 0.264521)
							(end -0.2032 0.2794)
						)
						(arc
							(start 0.2032 0.2794)
							(mid 0.239121 0.264521)
							(end 0.254 0.2286)
						)
						(arc
							(start 0.254 -0.2286)
							(mid 0.239121 -0.264521)
							(end 0.2032 -0.2794)
						)
					)
					(width 0)
					(fill yes)
				)
			)
		)
	)
)
